(kicad_pcb
	(version 20260206)
	(generator "pcbnew")
	(generator_version "10.0")
	(general
		(thickness 1.6)
		(legacy_teardrops no)
	)
	(paper "A4")
	(title_block
		(title "Bryce Canyon_SCC_16316-1_OCP.brd")
		(comment 1 "Bryce Canyon / footprints 87-94 of 1561")
	)
	(layers
		(0 "F.Cu" signal "TOP")
		(4 "In1.Cu" signal "L2GND")
		(6 "In2.Cu" signal "L3")
		(8 "In3.Cu" signal "L4VCC")
		(10 "In4.Cu" signal "L5VCC")
		(12 "In5.Cu" signal "L6")
		(14 "In6.Cu" signal "L7GND")
		(2 "B.Cu" signal "BOTTOM")
		(9 "F.Adhes" user "F.Adhesive")
		(11 "B.Adhes" user "B.Adhesive")
		(13 "F.Paste" user "Package Geometry/Pastemask Top")
		(15 "B.Paste" user "Package Geometry/Pastemask Bottom")
		(5 "F.SilkS" user "Ref Des/Silkscreen Top")
		(7 "B.SilkS" user "Ref Des/Silkscreen Bottom")
		(1 "F.Mask" user "Board Geometry/Soldermask Top")
		(3 "B.Mask" user "Board Geometry/Soldermask Bottom")
		(17 "Dwgs.User" user "User.Drawings")
		(19 "Cmts.User" user "User.Comments")
		(21 "Eco1.User" user "User.Eco1")
		(23 "Eco2.User" user "User.Eco2")
		(25 "Edge.Cuts" user "Board Geometry/Outline")
		(27 "Margin" user)
		(31 "F.CrtYd" user "Package Geometry/Place Bound Top")
		(29 "B.CrtYd" user "Package Geometry/Place Bound Bottom")
		(35 "F.Fab" user "Ref Des/Assembly Top")
		(33 "B.Fab" user "Ref Des/Assembly Bottom")
	)
	(footprint ""
		(layer "F.Cu")
		(at 152.164542 -96.25457 -90)
		(property "Reference" "R294"
			(at 0 0 270)
			(layer "F.SilkS")
			(hide yes)
			(effects
				(font
					(size 1.27 1.27)
				)
			)
		)
		(property "Value" "0R2J-2-GP"
			(at 0.064008 -3.993896 270)
			(unlocked yes)
			(layer "F.Fab")
			(hide yes)
			(effects
				(font
					(size 1.016 1.016)
					(thickness 0.1524)
				)
			)
		)
		(property "Device Type" "R402H16"
			(at 0.064008 -5.517896 270)
			(unlocked yes)
			(layer "F.Fab")
			(hide yes)
			(effects
				(font
					(size 1.016 1.016)
					(thickness 0.1524)
				)
			)
		)
		(duplicate_pad_numbers_are_jumpers no)
		(fp_line
			(start -0.508 -0.9398)
			(end -0.508 0.9398)
			(stroke
				(width 0.1524)
				(type default)
			)
			(layer "F.SilkS")
		)
		(fp_line
			(start 0.508 -0.9398)
			(end -0.508 -0.9398)
			(stroke
				(width 0.1524)
				(type default)
			)
			(layer "F.SilkS")
		)
		(fp_rect
			(start -0.508 0.9398)
			(end 0.508 -0.9398)
			(stroke
				(width 0)
				(type default)
			)
			(fill no)
			(layer "F.CrtYd")
		)
		(fp_rect
			(start -0.508 0.9398)
			(end 0.508 -0.9398)
			(stroke
				(width 0)
				(type default)
			)
			(fill no)
			(layer "F.Fab")
		)
		(pad "1" smd custom
			(at 0 -0.4445 270)
			(size 0.1397 0.1397)
			(layers "F.Cu" "F.Mask" "F.Paste")
			(net "SDB_RX_R")
			(options
				(clearance outline)
				(anchor circle)
			)
			(primitives
				(gr_poly
					(pts
						(arc
							(start -0.1778 -0.2794)
							(mid -0.249642 -0.249642)
							(end -0.2794 -0.1778)
						)
						(arc
							(start -0.2794 0.1778)
							(mid -0.249642 0.249642)
							(end -0.1778 0.2794)
						)
						(arc
							(start 0.1778 0.2794)
							(mid 0.249642 0.249642)
							(end 0.2794 0.1778)
						)
						(arc
							(start 0.2794 -0.1778)
							(mid 0.249642 -0.249642)
							(end 0.1778 -0.2794)
						)
					)
					(width 0)
					(fill yes)
				)
			)
		)
		(pad "2" smd custom
			(at 0 0.4445 270)
			(size 0.1397 0.1397)
			(layers "F.Cu" "F.Mask" "F.Paste")
			(net "SDB_RX")
			(options
				(clearance outline)
				(anchor circle)
			)
			(primitives
				(gr_poly
					(pts
						(arc
							(start -0.1778 -0.2794)
							(mid -0.249642 -0.249642)
							(end -0.2794 -0.1778)
						)
						(arc
							(start -0.2794 0.1778)
							(mid -0.249642 0.249642)
							(end -0.1778 0.2794)
						)
						(arc
							(start 0.1778 0.2794)
							(mid 0.249642 0.249642)
							(end 0.2794 0.1778)
						)
						(arc
							(start 0.2794 -0.1778)
							(mid 0.249642 -0.249642)
							(end 0.1778 -0.2794)
						)
					)
					(width 0)
					(fill yes)
				)
			)
		)
	)
	(footprint ""
		(layer "F.Cu")
		(at 104.7496 -86.889336 180)
		(property "Reference" "R403"
			(at 0 0 180)
			(layer "F.SilkS")
			(hide yes)
			(effects
				(font
					(size 1.27 1.27)
				)
			)
		)
		(property "Value" "10KR2F-2-GP"
			(at 0.064008 -3.993896 180)
			(unlocked yes)
			(layer "F.Fab")
			(hide yes)
			(effects
				(font
					(size 1.016 1.016)
					(thickness 0.1524)
				)
			)
		)
		(property "Device Type" "R402H16"
			(at 0.064008 -5.517896 180)
			(unlocked yes)
			(layer "F.Fab")
			(hide yes)
			(effects
				(font
					(size 1.016 1.016)
					(thickness 0.1524)
				)
			)
		)
		(duplicate_pad_numbers_are_jumpers no)
		(fp_line
			(start 0.508 -0.9398)
			(end -0.508 -0.9398)
			(stroke
				(width 0.1524)
				(type default)
			)
			(layer "F.SilkS")
		)
		(fp_line
			(start -0.508 -0.9398)
			(end -0.508 0.9398)
			(stroke
				(width 0.1524)
				(type default)
			)
			(layer "F.SilkS")
		)
		(fp_rect
			(start -0.508 0.9398)
			(end 0.508 -0.9398)
			(stroke
				(width 0)
				(type default)
			)
			(fill no)
			(layer "F.CrtYd")
		)
		(fp_rect
			(start -0.508 0.9398)
			(end 0.508 -0.9398)
			(stroke
				(width 0)
				(type default)
			)
			(fill no)
			(layer "F.Fab")
		)
		(pad "1" smd custom
			(at 0 -0.4445 180)
			(size 0.1397 0.1397)
			(layers "F.Cu" "F.Mask" "F.Paste")
			(net "SLOT_ID_0")
			(options
				(clearance outline)
				(anchor circle)
			)
			(primitives
				(gr_poly
					(pts
						(arc
							(start -0.1778 -0.2794)
							(mid -0.249642 -0.249642)
							(end -0.2794 -0.1778)
						)
						(arc
							(start -0.2794 0.1778)
							(mid -0.249642 0.249642)
							(end -0.1778 0.2794)
						)
						(arc
							(start 0.1778 0.2794)
							(mid 0.249642 0.249642)
							(end 0.2794 0.1778)
						)
						(arc
							(start 0.2794 -0.1778)
							(mid 0.249642 -0.249642)
							(end 0.1778 -0.2794)
						)
					)
					(width 0)
					(fill yes)
				)
			)
		)
		(pad "2" smd custom
			(at 0 0.4445 180)
			(size 0.1397 0.1397)
			(layers "F.Cu" "F.Mask" "F.Paste")
			(net "P1V8_E")
			(options
				(clearance outline)
				(anchor circle)
			)
			(primitives
				(gr_poly
					(pts
						(arc
							(start -0.1778 -0.2794)
							(mid -0.249642 -0.249642)
							(end -0.2794 -0.1778)
						)
						(arc
							(start -0.2794 0.1778)
							(mid -0.249642 0.249642)
							(end -0.1778 0.2794)
						)
						(arc
							(start 0.1778 0.2794)
							(mid 0.249642 0.249642)
							(end 0.2794 0.1778)
						)
						(arc
							(start 0.2794 -0.1778)
							(mid 0.249642 -0.249642)
							(end 0.1778 -0.2794)
						)
					)
					(width 0)
					(fill yes)
				)
			)
		)
	)
	(footprint ""
		(layer "F.Cu")
		(at 20.6502 -93.6752)
		(property "Reference" "R408"
			(at 0 0 0)
			(layer "F.SilkS")
			(hide yes)
			(effects
				(font
					(size 1.27 1.27)
				)
			)
		)
		(property "Value" "1KR2F-3-GP"
			(at 0.064008 -3.993896 0)
			(unlocked yes)
			(layer "F.Fab")
			(hide yes)
			(effects
				(font
					(size 1.016 1.016)
					(thickness 0.1524)
				)
			)
		)
		(property "Device Type" "R402H16"
			(at 0.064008 -5.517896 0)
			(unlocked yes)
			(layer "F.Fab")
			(hide yes)
			(effects
				(font
					(size 1.016 1.016)
					(thickness 0.1524)
				)
			)
		)
		(duplicate_pad_numbers_are_jumpers no)
		(fp_line
			(start -0.508 -0.9398)
			(end -0.508 0.9398)
			(stroke
				(width 0.1524)
				(type default)
			)
			(layer "F.SilkS")
		)
		(fp_line
			(start 0.508 -0.9398)
			(end -0.508 -0.9398)
			(stroke
				(width 0.1524)
				(type default)
			)
			(layer "F.SilkS")
		)
		(fp_rect
			(start -0.508 0.9398)
			(end 0.508 -0.9398)
			(stroke
				(width 0)
				(type default)
			)
			(fill no)
			(layer "F.CrtYd")
		)
		(fp_rect
			(start -0.508 0.9398)
			(end 0.508 -0.9398)
			(stroke
				(width 0)
				(type default)
			)
			(fill no)
			(layer "F.Fab")
		)
		(pad "1" smd custom
			(at 0 -0.4445)
			(size 0.1397 0.1397)
			(layers "F.Cu" "F.Mask" "F.Paste")
			(net "P3V3")
			(options
				(clearance outline)
				(anchor circle)
			)
			(primitives
				(gr_poly
					(pts
						(arc
							(start -0.1778 -0.2794)
							(mid -0.249642 -0.249642)
							(end -0.2794 -0.1778)
						)
						(arc
							(start -0.2794 0.1778)
							(mid -0.249642 0.249642)
							(end -0.1778 0.2794)
						)
						(arc
							(start 0.1778 0.2794)
							(mid 0.249642 0.249642)
							(end 0.2794 0.1778)
						)
						(arc
							(start 0.2794 -0.1778)
							(mid 0.249642 -0.249642)
							(end 0.1778 -0.2794)
						)
					)
					(width 0)
					(fill yes)
				)
			)
		)
		(pad "2" smd custom
			(at 0 0.4445)
			(size 0.1397 0.1397)
			(layers "F.Cu" "F.Mask" "F.Paste")
			(net "I2C_BMC_LOC_SDA0")
			(options
				(clearance outline)
				(anchor circle)
			)
			(primitives
				(gr_poly
					(pts
						(arc
							(start -0.1778 -0.2794)
							(mid -0.249642 -0.249642)
							(end -0.2794 -0.1778)
						)
						(arc
							(start -0.2794 0.1778)
							(mid -0.249642 0.249642)
							(end -0.1778 0.2794)
						)
						(arc
							(start 0.1778 0.2794)
							(mid 0.249642 0.249642)
							(end 0.2794 0.1778)
						)
						(arc
							(start 0.2794 -0.1778)
							(mid 0.249642 -0.249642)
							(end 0.1778 -0.2794)
						)
					)
					(width 0)
					(fill yes)
				)
			)
		)
	)
	(footprint ""
		(layer "F.Cu")
		(at 139.01801 -84.705952)
		(property "Reference" "R50"
			(at 0 0 0)
			(layer "F.SilkS")
			(hide yes)
			(effects
				(font
					(size 1.27 1.27)
				)
			)
		)
		(property "Value" "4K7R2F-GP"
			(at 0.064008 -3.993896 0)
			(unlocked yes)
			(layer "F.Fab")
			(hide yes)
			(effects
				(font
					(size 1.016 1.016)
					(thickness 0.1524)
				)
			)
		)
		(property "Device Type" "R402H16"
			(at 0.064008 -5.517896 0)
			(unlocked yes)
			(layer "F.Fab")
			(hide yes)
			(effects
				(font
					(size 1.016 1.016)
					(thickness 0.1524)
				)
			)
		)
		(duplicate_pad_numbers_are_jumpers no)
		(fp_line
			(start -0.508 -0.9398)
			(end -0.508 0.9398)
			(stroke
				(width 0.1524)
				(type default)
			)
			(layer "F.SilkS")
		)
		(fp_line
			(start 0.508 -0.9398)
			(end -0.508 -0.9398)
			(stroke
				(width 0.1524)
				(type default)
			)
			(layer "F.SilkS")
		)
		(fp_rect
			(start -0.508 0.9398)
			(end 0.508 -0.9398)
			(stroke
				(width 0)
				(type default)
			)
			(fill no)
			(layer "F.CrtYd")
		)
		(fp_rect
			(start -0.508 0.9398)
			(end 0.508 -0.9398)
			(stroke
				(width 0)
				(type default)
			)
			(fill no)
			(layer "F.Fab")
		)
		(pad "1" smd custom
			(at 0 -0.4445)
			(size 0.1397 0.1397)
			(layers "F.Cu" "F.Mask" "F.Paste")
			(net "P1V8_E")
			(options
				(clearance outline)
				(anchor circle)
			)
			(primitives
				(gr_poly
					(pts
						(arc
							(start -0.1778 -0.2794)
							(mid -0.249642 -0.249642)
							(end -0.2794 -0.1778)
						)
						(arc
							(start -0.2794 0.1778)
							(mid -0.249642 0.249642)
							(end -0.1778 0.2794)
						)
						(arc
							(start 0.1778 0.2794)
							(mid 0.249642 0.249642)
							(end 0.2794 0.1778)
						)
						(arc
							(start 0.2794 -0.1778)
							(mid 0.249642 -0.249642)
							(end 0.1778 -0.2794)
						)
					)
					(width 0)
					(fill yes)
				)
			)
		)
		(pad "2" smd custom
			(at 0 0.4445)
			(size 0.1397 0.1397)
			(layers "F.Cu" "F.Mask" "F.Paste")
			(net "I2C_BMC_RMT_SCL1_LS")
			(options
				(clearance outline)
				(anchor circle)
			)
			(primitives
				(gr_poly
					(pts
						(arc
							(start -0.1778 -0.2794)
							(mid -0.249642 -0.249642)
							(end -0.2794 -0.1778)
						)
						(arc
							(start -0.2794 0.1778)
							(mid -0.249642 0.249642)
							(end -0.1778 0.2794)
						)
						(arc
							(start 0.1778 0.2794)
							(mid 0.249642 0.249642)
							(end 0.2794 0.1778)
						)
						(arc
							(start 0.2794 -0.1778)
							(mid 0.249642 -0.249642)
							(end 0.1778 -0.2794)
						)
					)
					(width 0)
					(fill yes)
				)
			)
		)
	)
	(footprint ""
		(layer "F.Cu")
		(at 164.164772 -55.315612)
		(property "Reference" "TP128"
			(at 0 0 0)
			(layer "F.SilkS")
			(hide yes)
			(effects
				(font
					(size 1.27 1.27)
				)
			)
		)
		(property "Value" "TPAD28-2-GP"
			(at -0.0127 -1.6637 0)
			(unlocked yes)
			(layer "F.Fab")
			(hide yes)
			(effects
				(font
					(size 1.016 1.016)
					(thickness 0.1524)
				)
			)
		)
		(property "Device Type" "TPAD28"
			(at -0.0127 -3.1877 0)
			(unlocked yes)
			(layer "F.Fab")
			(hide yes)
			(effects
				(font
					(size 1.016 1.016)
					(thickness 0.1524)
				)
			)
		)
		(duplicate_pad_numbers_are_jumpers no)
		(fp_poly
			(pts
				(arc
					(start 0.3556 0)
					(mid -0.3556 0)
					(end 0.3556 0)
				)
			)
			(stroke
				(width 0)
				(type default)
			)
			(fill no)
			(layer "F.CrtYd")
		)
		(fp_poly
			(pts
				(arc
					(start 0.6096 0)
					(mid -0.6096 0)
					(end 0.6096 0)
				)
			)
			(stroke
				(width 0)
				(type default)
			)
			(fill no)
			(layer "F.Fab")
		)
		(pad "1" smd circle
			(at 0 0)
			(size 0.7112 0.7112)
			(layers "F.Cu" "F.Mask" "F.Paste")
			(net "ICE1_TRST#")
		)
	)
	(footprint ""
		(layer "F.Cu")
		(at 73.533 -51.689 180)
		(property "Reference" "C270"
			(at 0 0 180)
			(layer "F.SilkS")
			(hide yes)
			(effects
				(font
					(size 1.27 1.27)
				)
			)
		)
		(property "Value" "SC100U6D3V6MX-GP"
			(at -0.0762 -5.1308 180)
			(unlocked yes)
			(layer "F.Fab")
			(hide yes)
			(effects
				(font
					(size 1.016 1.016)
					(thickness 0.1524)
				)
			)
		)
		(property "Device Type" "C1206H71"
			(at -0.127 -6.6548 180)
			(unlocked yes)
			(layer "F.Fab")
			(hide yes)
			(effects
				(font
					(size 1.016 1.016)
					(thickness 0.1524)
				)
			)
		)
		(duplicate_pad_numbers_are_jumpers no)
		(fp_line
			(start 1.016 2.2352)
			(end -1.016 2.2352)
			(stroke
				(width 0.1524)
				(type default)
			)
			(layer "F.SilkS")
		)
		(fp_line
			(start 1.016 0.8382)
			(end 1.016 2.2352)
			(stroke
				(width 0.1524)
				(type default)
			)
			(layer "F.SilkS")
		)
		(fp_line
			(start 1.016 -2.2352)
			(end 1.016 -0.8382)
			(stroke
				(width 0.1524)
				(type default)
			)
			(layer "F.SilkS")
		)
		(fp_line
			(start -1.016 2.2352)
			(end -1.016 0.8382)
			(stroke
				(width 0.1524)
				(type default)
			)
			(layer "F.SilkS")
		)
		(fp_line
			(start -1.016 -0.8382)
			(end -1.016 -2.2352)
			(stroke
				(width 0.1524)
				(type default)
			)
			(layer "F.SilkS")
		)
		(fp_line
			(start -1.016 -2.2352)
			(end 1.016 -2.2352)
			(stroke
				(width 0.1524)
				(type default)
			)
			(layer "F.SilkS")
		)
		(fp_rect
			(start -1.0922 2.3114)
			(end 1.0922 -2.3114)
			(stroke
				(width 0)
				(type default)
			)
			(fill no)
			(layer "F.CrtYd")
		)
		(fp_poly
			(pts
				(xy 1.0922 -2.3114) (xy 1.0922 2.3114) (xy -1.0922 2.3114) (xy -1.0922 -2.3114)
			)
			(stroke
				(width 0)
				(type default)
			)
			(fill no)
			(layer "F.Fab")
		)
		(pad "1" smd rect
			(at 0 -1.397 180)
			(size 1.651 1.27)
			(layers "F.Cu" "F.Mask" "F.Paste")
			(net "GB_VDDA")
		)
		(pad "2" smd rect
			(at 0 1.397 180)
			(size 1.651 1.27)
			(layers "F.Cu" "F.Mask" "F.Paste")
			(net "GND")
		)
	)
	(footprint ""
		(layer "F.Cu")
		(at 174.8028 -82.677)
		(property "Reference" "L26"
			(at 0 0 0)
			(layer "F.SilkS")
			(hide yes)
			(effects
				(font
					(size 1.27 1.27)
				)
			)
		)
		(property "Value" "MPZ2012S300AT-GP"
			(at 0 -4.2418 0)
			(unlocked yes)
			(layer "F.Fab")
			(hide yes)
			(effects
				(font
					(size 1.016 1.016)
					(thickness 0.1524)
				)
			)
		)
		(property "Device Type" "L805H42"
			(at 0 -5.7912 0)
			(unlocked yes)
			(layer "F.Fab")
			(hide yes)
			(effects
				(font
					(size 1.016 1.016)
					(thickness 0.1524)
				)
			)
		)
		(duplicate_pad_numbers_are_jumpers no)
		(fp_line
			(start -0.889 -1.7018)
			(end 0.889 -1.7018)
			(stroke
				(width 0.1524)
				(type default)
			)
			(layer "F.SilkS")
		)
		(fp_line
			(start -0.889 1.7018)
			(end -0.889 -1.7018)
			(stroke
				(width 0.1524)
				(type default)
			)
			(layer "F.SilkS")
		)
		(fp_line
			(start 0.889 -1.7018)
			(end 0.889 1.7018)
			(stroke
				(width 0.1524)
				(type default)
			)
			(layer "F.SilkS")
		)
		(fp_line
			(start 0.889 1.7018)
			(end -0.889 1.7018)
			(stroke
				(width 0.1524)
				(type default)
			)
			(layer "F.SilkS")
		)
		(fp_rect
			(start -0.9652 1.778)
			(end 0.9652 -1.778)
			(stroke
				(width 0)
				(type default)
			)
			(fill no)
			(layer "F.CrtYd")
		)
		(fp_rect
			(start -0.9652 1.778)
			(end 0.9652 -1.778)
			(stroke
				(width 0)
				(type default)
			)
			(fill no)
			(layer "F.Fab")
		)
		(pad "1" smd rect
			(at 0 -0.9652)
			(size 1.397 1.143)
			(layers "F.Cu" "F.Mask" "F.Paste")
			(net "P0V975")
		)
		(pad "2" smd rect
			(at 0 0.9652)
			(size 1.397 1.143)
			(layers "F.Cu" "F.Mask" "F.Paste")
			(net "PCE_AVDD")
		)
	)
	(footprint ""
		(layer "F.Cu")
		(at 164.20084 -99.26828 90)
		(property "Reference" "C621"
			(at 0 0 90)
			(layer "F.SilkS")
			(hide yes)
			(effects
				(font
					(size 1.27 1.27)
				)
			)
		)
		(property "Value" "SC1U16V3KX-5GP"
			(at 0 -2.8194 90)
			(unlocked yes)
			(layer "F.Fab")
			(hide yes)
			(effects
				(font
					(size 1.016 1.016)
					(thickness 0.1524)
				)
			)
		)
		(property "Device Type" "C603H36"
			(at 0 -4.3434 90)
			(unlocked yes)
			(layer "F.Fab")
			(hide yes)
			(effects
				(font
					(size 1.016 1.016)
					(thickness 0.1524)
				)
			)
		)
		(duplicate_pad_numbers_are_jumpers no)
		(fp_line
			(start 0.508 0)
			(end -0.508 0)
			(stroke
				(width 0.2032)
				(type default)
			)
			(layer "F.SilkS")
		)
		(fp_rect
			(start -0.5842 1.3335)
			(end 0.5842 -1.3335)
			(stroke
				(width 0)
				(type default)
			)
			(fill no)
			(layer "F.CrtYd")
		)
		(fp_rect
			(start -0.5842 1.3335)
			(end 0.5842 -1.3335)
			(stroke
				(width 0)
				(type default)
			)
			(fill no)
			(layer "F.Fab")
		)
		(pad "1" smd custom
			(at 0 -0.762 90)
			(size 0.2159 0.2159)
			(layers "F.Cu" "F.Mask" "F.Paste")
			(net "GND")
			(options
				(clearance outline)
				(anchor circle)
			)
			(primitives
				(gr_poly
					(pts
						(arc
							(start -0.3302 -0.4318)
							(mid -0.402042 -0.402042)
							(end -0.4318 -0.3302)
						)
						(arc
							(start -0.4318 0.3302)
							(mid -0.402042 0.402042)
							(end -0.3302 0.4318)
						)
						(arc
							(start 0.3302 0.4318)
							(mid 0.402042 0.402042)
							(end 0.4318 0.3302)
						)
						(arc
							(start 0.4318 -0.3302)
							(mid 0.402042 -0.402042)
							(end 0.3302 -0.4318)
						)
					)
					(width 0)
					(fill yes)
				)
			)
		)
		(pad "2" smd custom
			(at 0 0.762 90)
			(size 0.2159 0.2159)
			(layers "F.Cu" "F.Mask" "F.Paste")
			(net "VT235_EN")
			(options
				(clearance outline)
				(anchor circle)
			)
			(primitives
				(gr_poly
					(pts
						(arc
							(start -0.3302 -0.4318)
							(mid -0.402042 -0.402042)
							(end -0.4318 -0.3302)
						)
						(arc
							(start -0.4318 0.3302)
							(mid -0.402042 0.402042)
							(end -0.3302 0.4318)
						)
						(arc
							(start 0.3302 0.4318)
							(mid 0.402042 0.402042)
							(end 0.4318 0.3302)
						)
						(arc
							(start 0.4318 -0.3302)
							(mid 0.402042 -0.402042)
							(end 0.3302 -0.4318)
						)
					)
					(width 0)
					(fill yes)
				)
			)
		)
	)
)
